FILE_TYPE=LIBRARY_PARTS;
primitive 'BAT547F';
  pin
    '1':
      PIN_NUMBER='(1)';
      BIDIRECTIONAL='TRUE';
      INPUT_LOAD='(-0.01,0.01)';
      OUTPUT_LOAD='(1.0,-1.0)';
    '3':
      PIN_NUMBER='(3)';
      BIDIRECTIONAL='TRUE';
      INPUT_LOAD='(-0.01,0.01)';
      OUTPUT_LOAD='(1.0,-1.0)';
  end_pin;
  body
    PART_NAME='BAT547F';
    BODY_NAME='BAT547F';
    PHYS_DES_PREFIX='D';
    CLASS='DISCRETE';
    NC_PINS='(2)';
  end_body;
end_primitive;

END.
